# T6G (Grand Teton) — schematic netlist excerpt (pin names and nets, part order shuffled) for the footprints in the layout excerpt that follows; sources: Cadence DE-HDL packaged netlist, KiCad conversion of 04192023_DAF0TMB3IC0_F0TG_MB_C_brd_V02_OCP.brd

R6770  Q_RES  4.7K 5% EMPTY  pkg 0201LF  page 184 : A = P1V8_AUX ; B = RT_SMB_MUX_ADDR2
C995  Q_CAP  10UF 6.3V 20% X6S  pkg C0402  page 312 : A = P1V8_CPU0_RT3_1A ; B = GND
L11  Q_INDUCTOR  BLM21SN300SN1D/5A IND  pkg SMLF  page 279 : \1\ = P1V8_CPU0_RT_1D ; \2\ = P1V8_CPU0_RT0_1A

(kicad_pcb
	(version 20260206)
	(generator "pcbnew")
	(generator_version "10.0")
	(general
		(thickness 1.6)
		(legacy_teardrops no)
	)
	(paper "A4")
	(title_block
		(title "04192023_DAF0TMB3IC0_F0TG_MB_C_brd_V02_OCP.brd")
		(comment 1 "Grand Teton / footprints 8235-8237 of 8354")
	)
	(layers
		(0 "F.Cu" signal "TOP")
		(4 "In1.Cu" signal "GND")
		(6 "In2.Cu" signal "IN1")
		(8 "In3.Cu" signal "GND1")
		(10 "In4.Cu" signal "IN2")
		(12 "In5.Cu" signal "GND2")
		(14 "In6.Cu" signal "IN3")
		(16 "In7.Cu" signal "GND3")
		(18 "In8.Cu" signal "VCC")
		(20 "In9.Cu" signal "VCC1")
		(22 "In10.Cu" signal "GND4")
		(24 "In11.Cu" signal "IN4")
		(26 "In12.Cu" signal "GND5")
		(28 "In13.Cu" signal "IN5")
		(30 "In14.Cu" signal "GND6")
		(32 "In15.Cu" signal "IN6")
		(34 "In16.Cu" signal "GND7")
		(2 "B.Cu" signal "BOTTOM")
		(9 "F.Adhes" user "F.Adhesive")
		(11 "B.Adhes" user "B.Adhesive")
		(13 "F.Paste" user "Package Geometry/Pastemask Top")
		(15 "B.Paste" user "Package Geometry/Pastemask Bottom")
		(5 "F.SilkS" user "Ref Des/Silkscreen Top")
		(7 "B.SilkS" user "Ref Des/Silkscreen Bottom")
		(1 "F.Mask" user "Board Geometry/Soldermask Top")
		(3 "B.Mask" user "Board Geometry/Soldermask Bottom")
		(17 "Dwgs.User" user "User.Drawings")
		(19 "Cmts.User" user "User.Comments")
		(21 "Eco1.User" user "User.Eco1")
		(23 "Eco2.User" user "User.Eco2")
		(25 "Edge.Cuts" user "Board Geometry/Outline")
		(27 "Margin" user)
		(31 "F.CrtYd" user "Package Geometry/Place Bound Top")
		(29 "B.CrtYd" user "Package Geometry/Place Bound Bottom")
		(35 "F.Fab" user "Ref Des/Assembly Top")
		(33 "B.Fab" user "Ref Des/Assembly Bottom")
	)
	(footprint ""
		(layer "B.Cu")
		(at 380.091188 -398.942052 90)
		(property "Reference" "C995"
			(at 0 0 90)
			(layer "B.SilkS")
			(hide yes)
			(effects
				(font
					(size 1.27 1.27)
				)
				(justify mirror)
			)
		)
		(property "Value" ""
			(at 0 0 90)
			(layer "B.Fab")
			(effects
				(font
					(size 1.27 1.27)
				)
				(justify mirror)
			)
		)
		(duplicate_pad_numbers_are_jumpers no)
		(fp_line
			(start 0.7874 -0.4064)
			(end -0.7874 -0.4064)
			(stroke
				(width 0.1524)
				(type default)
			)
			(layer "B.SilkS")
		)
		(fp_line
			(start -0.7874 -0.4064)
			(end -0.7874 0.4064)
			(stroke
				(width 0.1524)
				(type default)
			)
			(layer "B.SilkS")
		)
		(fp_line
			(start 0.7874 0.4064)
			(end 0.7874 -0.4064)
			(stroke
				(width 0.1524)
				(type default)
			)
			(layer "B.SilkS")
		)
		(fp_line
			(start -0.7874 0.4064)
			(end 0.7874 0.4064)
			(stroke
				(width 0.1524)
				(type default)
			)
			(layer "B.SilkS")
		)
		(fp_line
			(start 0.67945 -0.305054)
			(end 0.12065 -0.305054)
			(stroke
				(width 0.1)
				(type default)
			)
			(layer "B.Fab")
		)
		(fp_line
			(start 0.12065 -0.305054)
			(end 0.12065 -0.2794)
			(stroke
				(width 0.1)
				(type default)
			)
			(layer "B.Fab")
		)
		(fp_line
			(start -0.12065 -0.3048)
			(end -0.67945 -0.3048)
			(stroke
				(width 0.1)
				(type default)
			)
			(layer "B.Fab")
		)
		(fp_line
			(start -0.67945 -0.3048)
			(end -0.67945 0.3048)
			(stroke
				(width 0.1)
				(type default)
			)
			(layer "B.Fab")
		)
		(fp_line
			(start 0.12065 -0.2794)
			(end -0.12065 -0.2794)
			(stroke
				(width 0.1)
				(type default)
			)
			(layer "B.Fab")
		)
		(fp_line
			(start -0.12065 -0.2794)
			(end -0.12065 -0.3048)
			(stroke
				(width 0.1)
				(type default)
			)
			(layer "B.Fab")
		)
		(fp_line
			(start 0.12065 0.2794)
			(end 0.12065 0.3048)
			(stroke
				(width 0.1)
				(type default)
			)
			(layer "B.Fab")
		)
		(fp_line
			(start -0.120396 0.2794)
			(end 0.12065 0.2794)
			(stroke
				(width 0.1)
				(type default)
			)
			(layer "B.Fab")
		)
		(fp_line
			(start 0.67945 0.3048)
			(end 0.67945 -0.305054)
			(stroke
				(width 0.1)
				(type default)
			)
			(layer "B.Fab")
		)
		(fp_line
			(start 0.12065 0.3048)
			(end 0.67945 0.3048)
			(stroke
				(width 0.1)
				(type default)
			)
			(layer "B.Fab")
		)
		(fp_line
			(start -0.120396 0.3048)
			(end -0.120396 0.2794)
			(stroke
				(width 0.1)
				(type default)
			)
			(layer "B.Fab")
		)
		(fp_line
			(start -0.67945 0.3048)
			(end -0.120396 0.3048)
			(stroke
				(width 0.1)
				(type default)
			)
			(layer "B.Fab")
		)
		(pad "1" smd circle
			(at 0.40005 0 270)
			(size 0 0)
			(layers "B.Cu" "B.Mask" "B.Paste")
			(net "P1V8_CPU0_RT3_1A")
		)
		(pad "2" smd circle
			(at -0.40005 0 270)
			(size 0 0)
			(layers "B.Cu" "B.Mask" "B.Paste")
			(net "GND")
		)
	)
	(footprint ""
		(layer "B.Cu")
		(at 230.886 -332.74)
		(property "Reference" "R6770"
			(at 0 0 0)
			(layer "B.SilkS")
			(hide yes)
			(effects
				(font
					(size 1.27 1.27)
				)
				(justify mirror)
			)
		)
		(property "Value" ""
			(at 0 0 0)
			(layer "B.Fab")
			(effects
				(font
					(size 1.27 1.27)
				)
				(justify mirror)
			)
		)
		(duplicate_pad_numbers_are_jumpers no)
		(fp_line
			(start -0.32512 -0.175006)
			(end -0.32512 0.175006)
			(stroke
				(width 0.1)
				(type default)
			)
			(layer "B.Fab")
		)
		(fp_line
			(start -0.32512 0.175006)
			(end 0.32512 0.175006)
			(stroke
				(width 0.1)
				(type default)
			)
			(layer "B.Fab")
		)
		(fp_line
			(start 0.32512 -0.175006)
			(end -0.32512 -0.175006)
			(stroke
				(width 0.1)
				(type default)
			)
			(layer "B.Fab")
		)
		(fp_line
			(start 0.32512 0.175006)
			(end 0.32512 -0.175006)
			(stroke
				(width 0.1)
				(type default)
			)
			(layer "B.Fab")
		)
		(pad "1" smd rect
			(at 0.2667 0 180)
			(size 0.3048 0.381)
			(layers "B.Cu" "B.Mask" "B.Paste")
			(net "P1V8_AUX")
		)
		(pad "2" smd rect
			(at -0.2667 0)
			(size 0.3048 0.381)
			(layers "B.Cu" "B.Mask" "B.Paste")
			(net "RT_SMB_MUX_ADDR2")
		)
	)
	(footprint ""
		(layer "B.Cu")
		(at 326.252078 -392.957558)
		(property "Reference" "L11"
			(at 0 0 0)
			(layer "B.SilkS")
			(hide yes)
			(effects
				(font
					(size 1.27 1.27)
				)
				(justify mirror)
			)
		)
		(property "Value" ""
			(at 0 0 0)
			(layer "B.Fab")
			(effects
				(font
					(size 1.27 1.27)
				)
				(justify mirror)
			)
		)
		(duplicate_pad_numbers_are_jumpers no)
		(fp_line
			(start -1.63576 -0.8128)
			(end -1.63576 0.8128)
			(stroke
				(width 0.1524)
				(type default)
			)
			(layer "B.SilkS")
		)
		(fp_line
			(start -1.63576 0.8128)
			(end 1.63576 0.8128)
			(stroke
				(width 0.1524)
				(type default)
			)
			(layer "B.SilkS")
		)
		(fp_line
			(start 1.63576 -0.8128)
			(end -1.63576 -0.8128)
			(stroke
				(width 0.1524)
				(type default)
			)
			(layer "B.SilkS")
		)
		(fp_line
			(start 1.63576 -0.8128)
			(end 1.63576 0.8128)
			(stroke
				(width 0.1524)
				(type default)
			)
			(layer "B.SilkS")
		)
		(fp_line
			(start -1.560576 -0.738632)
			(end 1.56083 -0.738632)
			(stroke
				(width 0.1)
				(type default)
			)
			(layer "B.Fab")
		)
		(fp_line
			(start -1.560576 0.7366)
			(end -1.560576 -0.738632)
			(stroke
				(width 0.1)
				(type default)
			)
			(layer "B.Fab")
		)
		(fp_line
			(start -1.524 0.7366)
			(end -1.560576 0.7366)
			(stroke
				(width 0.1)
				(type default)
			)
			(layer "B.Fab")
		)
		(fp_line
			(start 1.524 0.7366)
			(end -1.524 0.7366)
			(stroke
				(width 0.1)
				(type default)
			)
			(layer "B.Fab")
		)
		(fp_line
			(start 1.56083 -0.738632)
			(end 1.56083 0.7366)
			(stroke
				(width 0.1)
				(type default)
			)
			(layer "B.Fab")
		)
		(fp_line
			(start 1.56083 0.7366)
			(end 1.524 0.7366)
			(stroke
				(width 0.1)
				(type default)
			)
			(layer "B.Fab")
		)
		(pad "1" smd rect
			(at 0.94996 0)
			(size 1.1176 1.3716)
			(layers "B.Cu" "B.Mask" "B.Paste")
			(net "P1V8_CPU0_RT_1D")
		)
		(pad "2" smd rect
			(at -0.94996 0)
			(size 1.1176 1.3716)
			(layers "B.Cu" "B.Mask" "B.Paste")
			(net "P1V8_CPU0_RT0_1A")
		)
	)
)
